# T6G (Grand Teton) — schematic netlist excerpt (pin names and nets, part order shuffled) for the footprints in the layout excerpt that follows; sources: Cadence DE-HDL packaged netlist, KiCad conversion of 04192023_DAF0TMB3IC0_F0TG_MB_C_brd_V02_OCP.brd

R6794  Q_RES  1K 1% EMPTY  pkg 0201LF  page 343 : A = P1V8_CPU1_RT_1D ; B = RT_CPU1_P2_VQPS
R9026  Q_RES  4.7K 5% CHIP  pkg 0402LF  page 85 : A = P3V3_AUX ; B = IRQ_HSC_FAULT
PC489  Q_CAP  0.22UF 16V 10% X7R  pkg 0402  page 194 : A = SW_PVDDCR_CPU0_P0_BOOT1_RC ; B = SW_PVDDCR_CPU0_P0_PH1

(kicad_pcb
	(version 20260206)
	(generator "pcbnew")
	(generator_version "10.0")
	(general
		(thickness 1.6)
		(legacy_teardrops no)
	)
	(paper "A4")
	(title_block
		(title "04192023_DAF0TMB3IC0_F0TG_MB_C_brd_V02_OCP.brd")
		(comment 1 "Grand Teton / footprints 77-79 of 8354")
	)
	(layers
		(0 "F.Cu" signal "TOP")
		(4 "In1.Cu" signal "GND")
		(6 "In2.Cu" signal "IN1")
		(8 "In3.Cu" signal "GND1")
		(10 "In4.Cu" signal "IN2")
		(12 "In5.Cu" signal "GND2")
		(14 "In6.Cu" signal "IN3")
		(16 "In7.Cu" signal "GND3")
		(18 "In8.Cu" signal "VCC")
		(20 "In9.Cu" signal "VCC1")
		(22 "In10.Cu" signal "GND4")
		(24 "In11.Cu" signal "IN4")
		(26 "In12.Cu" signal "GND5")
		(28 "In13.Cu" signal "IN5")
		(30 "In14.Cu" signal "GND6")
		(32 "In15.Cu" signal "IN6")
		(34 "In16.Cu" signal "GND7")
		(2 "B.Cu" signal "BOTTOM")
		(9 "F.Adhes" user "F.Adhesive")
		(11 "B.Adhes" user "B.Adhesive")
		(13 "F.Paste" user "Package Geometry/Pastemask Top")
		(15 "B.Paste" user "Package Geometry/Pastemask Bottom")
		(5 "F.SilkS" user "Ref Des/Silkscreen Top")
		(7 "B.SilkS" user "Ref Des/Silkscreen Bottom")
		(1 "F.Mask" user "Board Geometry/Soldermask Top")
		(3 "B.Mask" user "Board Geometry/Soldermask Bottom")
		(17 "Dwgs.User" user "User.Drawings")
		(19 "Cmts.User" user "User.Comments")
		(21 "Eco1.User" user "User.Eco1")
		(23 "Eco2.User" user "User.Eco2")
		(25 "Edge.Cuts" user "Board Geometry/Outline")
		(27 "Margin" user)
		(31 "F.CrtYd" user "Package Geometry/Place Bound Top")
		(29 "B.CrtYd" user "Package Geometry/Place Bound Bottom")
		(35 "F.Fab" user "Ref Des/Assembly Top")
		(33 "B.Fab" user "Ref Des/Assembly Bottom")
	)
	(footprint ""
		(layer "F.Cu")
		(at 362.528104 -173.119542 90)
		(property "Reference" "PC489"
			(at 0 0 90)
			(layer "F.SilkS")
			(hide yes)
			(effects
				(font
					(size 1.27 1.27)
				)
			)
		)
		(property "Value" ""
			(at 0 0 90)
			(layer "F.Fab")
			(effects
				(font
					(size 1.27 1.27)
				)
			)
		)
		(duplicate_pad_numbers_are_jumpers no)
		(fp_line
			(start 0.7874 -0.4064)
			(end 0.7874 0.4064)
			(stroke
				(width 0.1524)
				(type default)
			)
			(layer "F.SilkS")
		)
		(fp_line
			(start -0.7874 -0.4064)
			(end 0.7874 -0.4064)
			(stroke
				(width 0.1524)
				(type default)
			)
			(layer "F.SilkS")
		)
		(fp_line
			(start 0.7874 0.4064)
			(end -0.7874 0.4064)
			(stroke
				(width 0.1524)
				(type default)
			)
			(layer "F.SilkS")
		)
		(fp_line
			(start -0.7874 0.4064)
			(end -0.7874 -0.4064)
			(stroke
				(width 0.1524)
				(type default)
			)
			(layer "F.SilkS")
		)
		(fp_line
			(start -0.12065 -0.305054)
			(end -0.12065 -0.2794)
			(stroke
				(width 0.1)
				(type default)
			)
			(layer "F.Fab")
		)
		(fp_line
			(start -0.67945 -0.305054)
			(end -0.12065 -0.305054)
			(stroke
				(width 0.1)
				(type default)
			)
			(layer "F.Fab")
		)
		(fp_line
			(start 0.67945 -0.3048)
			(end 0.67945 0.3048)
			(stroke
				(width 0.1)
				(type default)
			)
			(layer "F.Fab")
		)
		(fp_line
			(start 0.12065 -0.3048)
			(end 0.67945 -0.3048)
			(stroke
				(width 0.1)
				(type default)
			)
			(layer "F.Fab")
		)
		(fp_line
			(start 0.12065 -0.2794)
			(end 0.12065 -0.3048)
			(stroke
				(width 0.1)
				(type default)
			)
			(layer "F.Fab")
		)
		(fp_line
			(start -0.12065 -0.2794)
			(end 0.12065 -0.2794)
			(stroke
				(width 0.1)
				(type default)
			)
			(layer "F.Fab")
		)
		(fp_line
			(start 0.120396 0.2794)
			(end -0.12065 0.2794)
			(stroke
				(width 0.1)
				(type default)
			)
			(layer "F.Fab")
		)
		(fp_line
			(start -0.12065 0.2794)
			(end -0.12065 0.3048)
			(stroke
				(width 0.1)
				(type default)
			)
			(layer "F.Fab")
		)
		(fp_line
			(start 0.67945 0.3048)
			(end 0.120396 0.3048)
			(stroke
				(width 0.1)
				(type default)
			)
			(layer "F.Fab")
		)
		(fp_line
			(start 0.120396 0.3048)
			(end 0.120396 0.2794)
			(stroke
				(width 0.1)
				(type default)
			)
			(layer "F.Fab")
		)
		(fp_line
			(start -0.12065 0.3048)
			(end -0.67945 0.3048)
			(stroke
				(width 0.1)
				(type default)
			)
			(layer "F.Fab")
		)
		(fp_line
			(start -0.67945 0.3048)
			(end -0.67945 -0.305054)
			(stroke
				(width 0.1)
				(type default)
			)
			(layer "F.Fab")
		)
		(pad "1" smd circle
			(at -0.40005 0 90)
			(size 0 0)
			(layers "F.Cu" "F.Mask" "F.Paste")
			(net "SW_PVDDCR_CPU0_P0_BOOT1_RC")
		)
		(pad "2" smd circle
			(at 0.40005 0 90)
			(size 0 0)
			(layers "F.Cu" "F.Mask" "F.Paste")
			(net "SW_PVDDCR_CPU0_P0_PH1")
		)
	)
	(footprint ""
		(layer "F.Cu")
		(at 159.893 -108.458 180)
		(property "Reference" "R9026"
			(at 0 0 180)
			(layer "F.SilkS")
			(hide yes)
			(effects
				(font
					(size 1.27 1.27)
				)
			)
		)
		(property "Value" ""
			(at 0 0 180)
			(layer "F.Fab")
			(effects
				(font
					(size 1.27 1.27)
				)
			)
		)
		(duplicate_pad_numbers_are_jumpers no)
		(fp_line
			(start 0.7874 0.4064)
			(end -0.7874 0.4064)
			(stroke
				(width 0.1524)
				(type default)
			)
			(layer "F.SilkS")
		)
		(fp_line
			(start 0.7874 -0.4064)
			(end 0.7874 0.4064)
			(stroke
				(width 0.1524)
				(type default)
			)
			(layer "F.SilkS")
		)
		(fp_line
			(start -0.7874 0.4064)
			(end -0.7874 -0.4064)
			(stroke
				(width 0.1524)
				(type default)
			)
			(layer "F.SilkS")
		)
		(fp_line
			(start -0.7874 -0.4064)
			(end 0.7874 -0.4064)
			(stroke
				(width 0.1524)
				(type default)
			)
			(layer "F.SilkS")
		)
		(fp_line
			(start 0.67945 0.3048)
			(end 0.120396 0.3048)
			(stroke
				(width 0.1)
				(type default)
			)
			(layer "F.Fab")
		)
		(fp_line
			(start 0.67945 -0.3048)
			(end 0.67945 0.3048)
			(stroke
				(width 0.1)
				(type default)
			)
			(layer "F.Fab")
		)
		(fp_line
			(start 0.12065 -0.2794)
			(end 0.12065 -0.3048)
			(stroke
				(width 0.1)
				(type default)
			)
			(layer "F.Fab")
		)
		(fp_line
			(start 0.12065 -0.3048)
			(end 0.67945 -0.3048)
			(stroke
				(width 0.1)
				(type default)
			)
			(layer "F.Fab")
		)
		(fp_line
			(start 0.120396 0.3048)
			(end 0.120396 0.2794)
			(stroke
				(width 0.1)
				(type default)
			)
			(layer "F.Fab")
		)
		(fp_line
			(start 0.120396 0.2794)
			(end -0.12065 0.2794)
			(stroke
				(width 0.1)
				(type default)
			)
			(layer "F.Fab")
		)
		(fp_line
			(start -0.12065 0.3048)
			(end -0.67945 0.3048)
			(stroke
				(width 0.1)
				(type default)
			)
			(layer "F.Fab")
		)
		(fp_line
			(start -0.12065 0.2794)
			(end -0.12065 0.3048)
			(stroke
				(width 0.1)
				(type default)
			)
			(layer "F.Fab")
		)
		(fp_line
			(start -0.12065 -0.2794)
			(end 0.12065 -0.2794)
			(stroke
				(width 0.1)
				(type default)
			)
			(layer "F.Fab")
		)
		(fp_line
			(start -0.12065 -0.305054)
			(end -0.12065 -0.2794)
			(stroke
				(width 0.1)
				(type default)
			)
			(layer "F.Fab")
		)
		(fp_line
			(start -0.67945 0.3048)
			(end -0.67945 -0.305054)
			(stroke
				(width 0.1)
				(type default)
			)
			(layer "F.Fab")
		)
		(fp_line
			(start -0.67945 -0.305054)
			(end -0.12065 -0.305054)
			(stroke
				(width 0.1)
				(type default)
			)
			(layer "F.Fab")
		)
		(pad "1" smd circle
			(at -0.40005 0 180)
			(size 0 0)
			(layers "F.Cu" "F.Mask" "F.Paste")
			(net "P3V3_AUX")
		)
		(pad "2" smd circle
			(at 0.40005 0 180)
			(size 0 0)
			(layers "F.Cu" "F.Mask" "F.Paste")
			(net "IRQ_HSC_FAULT")
		)
	)
	(footprint ""
		(layer "F.Cu")
		(at 166.18077 -395.6304 -90)
		(property "Reference" "R6794"
			(at 0 0 270)
			(layer "F.SilkS")
			(hide yes)
			(effects
				(font
					(size 1.27 1.27)
				)
			)
		)
		(property "Value" ""
			(at 0 0 270)
			(layer "F.Fab")
			(effects
				(font
					(size 1.27 1.27)
				)
			)
		)
		(duplicate_pad_numbers_are_jumpers no)
		(fp_line
			(start -0.32512 0.175006)
			(end -0.32512 -0.175006)
			(stroke
				(width 0.1)
				(type default)
			)
			(layer "F.Fab")
		)
		(fp_line
			(start 0.32512 0.175006)
			(end -0.32512 0.175006)
			(stroke
				(width 0.1)
				(type default)
			)
			(layer "F.Fab")
		)
		(fp_line
			(start -0.32512 -0.175006)
			(end 0.32512 -0.175006)
			(stroke
				(width 0.1)
				(type default)
			)
			(layer "F.Fab")
		)
		(fp_line
			(start 0.32512 -0.175006)
			(end 0.32512 0.175006)
			(stroke
				(width 0.1)
				(type default)
			)
			(layer "F.Fab")
		)
		(pad "1" smd rect
			(at -0.2667 0 270)
			(size 0.3048 0.381)
			(layers "F.Cu" "F.Mask" "F.Paste")
			(net "P1V8_CPU1_RT_1D")
		)
		(pad "2" smd rect
			(at 0.2667 0 90)
			(size 0.3048 0.381)
			(layers "F.Cu" "F.Mask" "F.Paste")
			(net "RT_CPU1_P2_VQPS")
		)
	)
)
